# S9S_MB_2U (Grand Teton) — schematic netlist excerpt (pin names and nets, part order shuffled) for the footprints in the layout excerpt that follows; sources: Cadence DE-HDL packaged netlist, KiCad conversion of 03242023_DA0F0TMBIJ0_F0T_Motherboard_J_brd_V01_OCP.brd

PR317  Q_RES  0 5% CHIP  pkg 0402LF  page 284 : A = SH_PVCCIN_CPU1 ; B = SH_PVCCIN_CPU1_R
PR3993  Q_RES  0 5% CHIP  pkg 0402LF  page 303 : A = HSC_FLT_TYPE_3 ; B = HSC_FLT_TYPE

(kicad_pcb
	(version 20260206)
	(generator "pcbnew")
	(generator_version "10.0")
	(general
		(thickness 1.6)
		(legacy_teardrops no)
	)
	(paper "A4")
	(title_block
		(title "03242023_DA0F0TMBIJ0_F0T_Motherboard_J_brd_V01_OCP.brd")
		(comment 1 "Grand Teton / footprints 2610-2611 of 6105")
	)
	(layers
		(0 "F.Cu" signal "TOP")
		(4 "In1.Cu" signal "GND")
		(6 "In2.Cu" signal "IN1")
		(8 "In3.Cu" signal "GND1")
		(10 "In4.Cu" signal "IN2")
		(12 "In5.Cu" signal "GND2")
		(14 "In6.Cu" signal "IN3")
		(16 "In7.Cu" signal "GND3")
		(18 "In8.Cu" signal "VCC")
		(20 "In9.Cu" signal "VCC1")
		(22 "In10.Cu" signal "GND4")
		(24 "In11.Cu" signal "IN4")
		(26 "In12.Cu" signal "GND5")
		(28 "In13.Cu" signal "IN5")
		(30 "In14.Cu" signal "GND6")
		(32 "In15.Cu" signal "IN6")
		(34 "In16.Cu" signal "GND7")
		(2 "B.Cu" signal "BOTTOM")
		(9 "F.Adhes" user "F.Adhesive")
		(11 "B.Adhes" user "B.Adhesive")
		(13 "F.Paste" user "Package Geometry/Pastemask Top")
		(15 "B.Paste" user "Package Geometry/Pastemask Bottom")
		(5 "F.SilkS" user "Ref Des/Silkscreen Top")
		(7 "B.SilkS" user "Ref Des/Silkscreen Bottom")
		(1 "F.Mask" user "Board Geometry/Soldermask Top")
		(3 "B.Mask" user "Board Geometry/Soldermask Bottom")
		(17 "Dwgs.User" user "User.Drawings")
		(19 "Cmts.User" user "User.Comments")
		(21 "Eco1.User" user "User.Eco1")
		(23 "Eco2.User" user "User.Eco2")
		(25 "Edge.Cuts" user "Board Geometry/Outline")
		(27 "Margin" user)
		(31 "F.CrtYd" user "Package Geometry/Place Bound Top")
		(29 "B.CrtYd" user "Package Geometry/Place Bound Bottom")
		(35 "F.Fab" user "Ref Des/Assembly Top")
		(33 "B.Fab" user "Ref Des/Assembly Bottom")
	)
	(footprint ""
		(layer "F.Cu")
		(at 226.733608 -406.855422)
		(property "Reference" "PR3993"
			(at 0 0 0)
			(layer "F.SilkS")
			(hide yes)
			(effects
				(font
					(size 1.27 1.27)
				)
			)
		)
		(property "Value" ""
			(at 0 0 0)
			(layer "F.Fab")
			(effects
				(font
					(size 1.27 1.27)
				)
			)
		)
		(duplicate_pad_numbers_are_jumpers no)
		(fp_line
			(start -0.7874 -0.4064)
			(end 0.7874 -0.4064)
			(stroke
				(width 0.1524)
				(type default)
			)
			(layer "F.SilkS")
		)
		(fp_line
			(start -0.7874 0.4064)
			(end -0.7874 -0.4064)
			(stroke
				(width 0.1524)
				(type default)
			)
			(layer "F.SilkS")
		)
		(fp_line
			(start 0.7874 -0.4064)
			(end 0.7874 0.4064)
			(stroke
				(width 0.1524)
				(type default)
			)
			(layer "F.SilkS")
		)
		(fp_line
			(start 0.7874 0.4064)
			(end -0.7874 0.4064)
			(stroke
				(width 0.1524)
				(type default)
			)
			(layer "F.SilkS")
		)
		(fp_line
			(start -0.67945 -0.305054)
			(end -0.12065 -0.305054)
			(stroke
				(width 0.1)
				(type default)
			)
			(layer "F.Fab")
		)
		(fp_line
			(start -0.67945 0.3048)
			(end -0.67945 -0.305054)
			(stroke
				(width 0.1)
				(type default)
			)
			(layer "F.Fab")
		)
		(fp_line
			(start -0.12065 -0.305054)
			(end -0.12065 -0.2794)
			(stroke
				(width 0.1)
				(type default)
			)
			(layer "F.Fab")
		)
		(fp_line
			(start -0.12065 -0.2794)
			(end 0.12065 -0.2794)
			(stroke
				(width 0.1)
				(type default)
			)
			(layer "F.Fab")
		)
		(fp_line
			(start -0.12065 0.2794)
			(end -0.12065 0.3048)
			(stroke
				(width 0.1)
				(type default)
			)
			(layer "F.Fab")
		)
		(fp_line
			(start -0.12065 0.3048)
			(end -0.67945 0.3048)
			(stroke
				(width 0.1)
				(type default)
			)
			(layer "F.Fab")
		)
		(fp_line
			(start 0.120396 0.2794)
			(end -0.12065 0.2794)
			(stroke
				(width 0.1)
				(type default)
			)
			(layer "F.Fab")
		)
		(fp_line
			(start 0.120396 0.3048)
			(end 0.120396 0.2794)
			(stroke
				(width 0.1)
				(type default)
			)
			(layer "F.Fab")
		)
		(fp_line
			(start 0.12065 -0.3048)
			(end 0.67945 -0.3048)
			(stroke
				(width 0.1)
				(type default)
			)
			(layer "F.Fab")
		)
		(fp_line
			(start 0.12065 -0.2794)
			(end 0.12065 -0.3048)
			(stroke
				(width 0.1)
				(type default)
			)
			(layer "F.Fab")
		)
		(fp_line
			(start 0.67945 -0.3048)
			(end 0.67945 0.3048)
			(stroke
				(width 0.1)
				(type default)
			)
			(layer "F.Fab")
		)
		(fp_line
			(start 0.67945 0.3048)
			(end 0.120396 0.3048)
			(stroke
				(width 0.1)
				(type default)
			)
			(layer "F.Fab")
		)
		(pad "1" smd circle
			(at -0.40005 0)
			(size 0 0)
			(layers "F.Cu" "F.Mask" "F.Paste")
			(net "HSC_FLT_TYPE_3")
		)
		(pad "2" smd circle
			(at 0.40005 0)
			(size 0 0)
			(layers "F.Cu" "F.Mask" "F.Paste")
			(net "HSC_FLT_TYPE")
		)
	)
	(footprint ""
		(layer "F.Cu")
		(at 104.22001 -353.14255)
		(property "Reference" "PR317"
			(at 0 0 0)
			(layer "F.SilkS")
			(hide yes)
			(effects
				(font
					(size 1.27 1.27)
				)
			)
		)
		(property "Value" ""
			(at 0 0 0)
			(layer "F.Fab")
			(effects
				(font
					(size 1.27 1.27)
				)
			)
		)
		(duplicate_pad_numbers_are_jumpers no)
		(fp_line
			(start -0.7874 -0.4064)
			(end 0.7874 -0.4064)
			(stroke
				(width 0.1524)
				(type default)
			)
			(layer "F.SilkS")
		)
		(fp_line
			(start -0.7874 0.4064)
			(end -0.7874 -0.4064)
			(stroke
				(width 0.1524)
				(type default)
			)
			(layer "F.SilkS")
		)
		(fp_line
			(start 0.7874 -0.4064)
			(end 0.7874 0.4064)
			(stroke
				(width 0.1524)
				(type default)
			)
			(layer "F.SilkS")
		)
		(fp_line
			(start 0.7874 0.4064)
			(end -0.7874 0.4064)
			(stroke
				(width 0.1524)
				(type default)
			)
			(layer "F.SilkS")
		)
		(fp_line
			(start -0.67945 -0.305054)
			(end -0.12065 -0.305054)
			(stroke
				(width 0.1)
				(type default)
			)
			(layer "F.Fab")
		)
		(fp_line
			(start -0.67945 0.3048)
			(end -0.67945 -0.305054)
			(stroke
				(width 0.1)
				(type default)
			)
			(layer "F.Fab")
		)
		(fp_line
			(start -0.12065 -0.305054)
			(end -0.12065 -0.2794)
			(stroke
				(width 0.1)
				(type default)
			)
			(layer "F.Fab")
		)
		(fp_line
			(start -0.12065 -0.2794)
			(end 0.12065 -0.2794)
			(stroke
				(width 0.1)
				(type default)
			)
			(layer "F.Fab")
		)
		(fp_line
			(start -0.12065 0.2794)
			(end -0.12065 0.3048)
			(stroke
				(width 0.1)
				(type default)
			)
			(layer "F.Fab")
		)
		(fp_line
			(start -0.12065 0.3048)
			(end -0.67945 0.3048)
			(stroke
				(width 0.1)
				(type default)
			)
			(layer "F.Fab")
		)
		(fp_line
			(start 0.120396 0.2794)
			(end -0.12065 0.2794)
			(stroke
				(width 0.1)
				(type default)
			)
			(layer "F.Fab")
		)
		(fp_line
			(start 0.120396 0.3048)
			(end 0.120396 0.2794)
			(stroke
				(width 0.1)
				(type default)
			)
			(layer "F.Fab")
		)
		(fp_line
			(start 0.12065 -0.3048)
			(end 0.67945 -0.3048)
			(stroke
				(width 0.1)
				(type default)
			)
			(layer "F.Fab")
		)
		(fp_line
			(start 0.12065 -0.2794)
			(end 0.12065 -0.3048)
			(stroke
				(width 0.1)
				(type default)
			)
			(layer "F.Fab")
		)
		(fp_line
			(start 0.67945 -0.3048)
			(end 0.67945 0.3048)
			(stroke
				(width 0.1)
				(type default)
			)
			(layer "F.Fab")
		)
		(fp_line
			(start 0.67945 0.3048)
			(end 0.120396 0.3048)
			(stroke
				(width 0.1)
				(type default)
			)
			(layer "F.Fab")
		)
		(pad "1" smd circle
			(at -0.40005 0)
			(size 0 0)
			(layers "F.Cu" "F.Mask" "F.Paste")
			(net "SH_PVCCIN_CPU1")
		)
		(pad "2" smd circle
			(at 0.40005 0)
			(size 0 0)
			(layers "F.Cu" "F.Mask" "F.Paste")
			(net "SH_PVCCIN_CPU1_R")
		)
	)
)
